(kicad_pcb
	(version 20260206)
	(generator "pcbnew")
	(generator_version "10.0")
	(general
		(thickness 1.6)
		(legacy_teardrops no)
	)
	(paper "A4")
	(title_block
		(title "01162023_DA0F0TEBIF0_F0T_Expander_BD_F_brd_V02_OCP.brd")
		(comment 1 "Grand Teton / footprints 883-889 of 9728")
	)
	(layers
		(0 "F.Cu" signal "TOP")
		(4 "In1.Cu" signal "GND")
		(6 "In2.Cu" signal "VCC")
		(8 "In3.Cu" signal "VCC1")
		(10 "In4.Cu" signal "GND1")
		(12 "In5.Cu" signal "IN1")
		(14 "In6.Cu" signal "GND2")
		(16 "In7.Cu" signal "IN2")
		(18 "In8.Cu" signal "GND3")
		(20 "In9.Cu" signal "IN3")
		(22 "In10.Cu" signal "GND4")
		(24 "In11.Cu" signal "IN4")
		(26 "In12.Cu" signal "GND5")
		(28 "In13.Cu" signal "IN5")
		(30 "In14.Cu" signal "GND6")
		(32 "In15.Cu" signal "IN6")
		(34 "In16.Cu" signal "GND7")
		(2 "B.Cu" signal "BOTTOM")
		(9 "F.Adhes" user "F.Adhesive")
		(11 "B.Adhes" user "B.Adhesive")
		(13 "F.Paste" user "Package Geometry/Pastemask Top")
		(15 "B.Paste" user "Package Geometry/Pastemask Bottom")
		(5 "F.SilkS" user "Ref Des/Silkscreen Top")
		(7 "B.SilkS" user "Ref Des/Silkscreen Bottom")
		(1 "F.Mask" user "Board Geometry/Soldermask Top")
		(3 "B.Mask" user "Board Geometry/Soldermask Bottom")
		(17 "Dwgs.User" user "User.Drawings")
		(19 "Cmts.User" user "User.Comments")
		(21 "Eco1.User" user "User.Eco1")
		(23 "Eco2.User" user "User.Eco2")
		(25 "Edge.Cuts" user "Board Geometry/Outline")
		(27 "Margin" user)
		(31 "F.CrtYd" user "Package Geometry/Place Bound Top")
		(29 "B.CrtYd" user "Package Geometry/Place Bound Bottom")
		(35 "F.Fab" user "Ref Des/Assembly Top")
		(33 "B.Fab" user "Ref Des/Assembly Bottom")
	)
	(footprint ""
		(layer "F.Cu")
		(at 94.216474 -92.929456 -90)
		(property "Reference" "R687"
			(at 0 0 270)
			(layer "F.SilkS")
			(hide yes)
			(effects
				(font
					(size 1.27 1.27)
				)
			)
		)
		(property "Value" ""
			(at 0 0 270)
			(layer "F.Fab")
			(effects
				(font
					(size 1.27 1.27)
				)
			)
		)
		(duplicate_pad_numbers_are_jumpers no)
		(fp_line
			(start -0.7874 0.4064)
			(end -0.7874 -0.4064)
			(stroke
				(width 0.1524)
				(type default)
			)
			(layer "F.SilkS")
		)
		(fp_line
			(start 0.7874 0.4064)
			(end -0.7874 0.4064)
			(stroke
				(width 0.1524)
				(type default)
			)
			(layer "F.SilkS")
		)
		(fp_line
			(start -0.7874 -0.4064)
			(end 0.7874 -0.4064)
			(stroke
				(width 0.1524)
				(type default)
			)
			(layer "F.SilkS")
		)
		(fp_line
			(start 0.7874 -0.4064)
			(end 0.7874 0.4064)
			(stroke
				(width 0.1524)
				(type default)
			)
			(layer "F.SilkS")
		)
		(fp_line
			(start -0.67945 0.3048)
			(end -0.67945 -0.305054)
			(stroke
				(width 0.1)
				(type default)
			)
			(layer "F.Fab")
		)
		(fp_line
			(start -0.12065 0.3048)
			(end -0.67945 0.3048)
			(stroke
				(width 0.1)
				(type default)
			)
			(layer "F.Fab")
		)
		(fp_line
			(start 0.120396 0.3048)
			(end 0.120396 0.2794)
			(stroke
				(width 0.1)
				(type default)
			)
			(layer "F.Fab")
		)
		(fp_line
			(start 0.67945 0.3048)
			(end 0.120396 0.3048)
			(stroke
				(width 0.1)
				(type default)
			)
			(layer "F.Fab")
		)
		(fp_line
			(start -0.12065 0.2794)
			(end -0.12065 0.3048)
			(stroke
				(width 0.1)
				(type default)
			)
			(layer "F.Fab")
		)
		(fp_line
			(start 0.120396 0.2794)
			(end -0.12065 0.2794)
			(stroke
				(width 0.1)
				(type default)
			)
			(layer "F.Fab")
		)
		(fp_line
			(start -0.12065 -0.2794)
			(end 0.12065 -0.2794)
			(stroke
				(width 0.1)
				(type default)
			)
			(layer "F.Fab")
		)
		(fp_line
			(start 0.12065 -0.2794)
			(end 0.12065 -0.3048)
			(stroke
				(width 0.1)
				(type default)
			)
			(layer "F.Fab")
		)
		(fp_line
			(start 0.12065 -0.3048)
			(end 0.67945 -0.3048)
			(stroke
				(width 0.1)
				(type default)
			)
			(layer "F.Fab")
		)
		(fp_line
			(start 0.67945 -0.3048)
			(end 0.67945 0.3048)
			(stroke
				(width 0.1)
				(type default)
			)
			(layer "F.Fab")
		)
		(fp_line
			(start -0.67945 -0.305054)
			(end -0.12065 -0.305054)
			(stroke
				(width 0.1)
				(type default)
			)
			(layer "F.Fab")
		)
		(fp_line
			(start -0.12065 -0.305054)
			(end -0.12065 -0.2794)
			(stroke
				(width 0.1)
				(type default)
			)
			(layer "F.Fab")
		)
		(pad "1" smd circle
			(at -0.40005 0 270)
			(size 0 0)
			(layers "F.Cu" "F.Mask" "F.Paste")
			(net "SMB_BIC_I2C6_MUX_NIC_ADC_R_SCL")
		)
		(pad "2" smd circle
			(at 0.40005 0 270)
			(size 0 0)
			(layers "F.Cu" "F.Mask" "F.Paste")
			(net "SMB_NIC0_ADC_SCL")
		)
	)
	(footprint ""
		(layer "F.Cu")
		(at 87.132922 -356.244906 90)
		(property "Reference" "C154"
			(at 0 0 90)
			(layer "F.SilkS")
			(hide yes)
			(effects
				(font
					(size 1.27 1.27)
				)
			)
		)
		(property "Value" ""
			(at 0 0 90)
			(layer "F.Fab")
			(effects
				(font
					(size 1.27 1.27)
				)
			)
		)
		(duplicate_pad_numbers_are_jumpers no)
		(fp_line
			(start 0.299974 -0.150114)
			(end 0.299974 0.150114)
			(stroke
				(width 0.1)
				(type default)
			)
			(layer "F.Fab")
		)
		(fp_line
			(start -0.299974 -0.150114)
			(end 0.299974 -0.150114)
			(stroke
				(width 0.1)
				(type default)
			)
			(layer "F.Fab")
		)
		(fp_line
			(start 0.299974 0.150114)
			(end -0.299974 0.150114)
			(stroke
				(width 0.1)
				(type default)
			)
			(layer "F.Fab")
		)
		(fp_line
			(start -0.299974 0.150114)
			(end -0.299974 -0.150114)
			(stroke
				(width 0.1)
				(type default)
			)
			(layer "F.Fab")
		)
		(pad "1" smd rect
			(at -0.2667 0 90)
			(size 0.3048 0.381)
			(layers "F.Cu" "F.Mask" "F.Paste")
			(net "P5E_PEX0_STN6_TX_DN<99>")
		)
		(pad "2" smd rect
			(at 0.2667 0 90)
			(size 0.3048 0.381)
			(layers "F.Cu" "F.Mask" "F.Paste")
			(net "P5E_PEX0_STN6_TX_C_DN<99>")
		)
	)
	(footprint ""
		(layer "F.Cu")
		(at 430.172114 -32.848042 90)
		(property "Reference" "PC975"
			(at 0 0 90)
			(layer "F.SilkS")
			(hide yes)
			(effects
				(font
					(size 1.27 1.27)
				)
			)
		)
		(property "Value" ""
			(at 0 0 90)
			(layer "F.Fab")
			(effects
				(font
					(size 1.27 1.27)
				)
			)
		)
		(duplicate_pad_numbers_are_jumpers no)
		(fp_line
			(start 0.7874 -0.4064)
			(end 0.7874 0.4064)
			(stroke
				(width 0.1524)
				(type default)
			)
			(layer "F.SilkS")
		)
		(fp_line
			(start -0.7874 -0.4064)
			(end 0.7874 -0.4064)
			(stroke
				(width 0.1524)
				(type default)
			)
			(layer "F.SilkS")
		)
		(fp_line
			(start 0.7874 0.4064)
			(end -0.7874 0.4064)
			(stroke
				(width 0.1524)
				(type default)
			)
			(layer "F.SilkS")
		)
		(fp_line
			(start -0.7874 0.4064)
			(end -0.7874 -0.4064)
			(stroke
				(width 0.1524)
				(type default)
			)
			(layer "F.SilkS")
		)
		(fp_line
			(start -0.12065 -0.305054)
			(end -0.12065 -0.2794)
			(stroke
				(width 0.1)
				(type default)
			)
			(layer "F.Fab")
		)
		(fp_line
			(start -0.67945 -0.305054)
			(end -0.12065 -0.305054)
			(stroke
				(width 0.1)
				(type default)
			)
			(layer "F.Fab")
		)
		(fp_line
			(start 0.67945 -0.3048)
			(end 0.67945 0.3048)
			(stroke
				(width 0.1)
				(type default)
			)
			(layer "F.Fab")
		)
		(fp_line
			(start 0.12065 -0.3048)
			(end 0.67945 -0.3048)
			(stroke
				(width 0.1)
				(type default)
			)
			(layer "F.Fab")
		)
		(fp_line
			(start 0.12065 -0.2794)
			(end 0.12065 -0.3048)
			(stroke
				(width 0.1)
				(type default)
			)
			(layer "F.Fab")
		)
		(fp_line
			(start -0.12065 -0.2794)
			(end 0.12065 -0.2794)
			(stroke
				(width 0.1)
				(type default)
			)
			(layer "F.Fab")
		)
		(fp_line
			(start 0.120396 0.2794)
			(end -0.12065 0.2794)
			(stroke
				(width 0.1)
				(type default)
			)
			(layer "F.Fab")
		)
		(fp_line
			(start -0.12065 0.2794)
			(end -0.12065 0.3048)
			(stroke
				(width 0.1)
				(type default)
			)
			(layer "F.Fab")
		)
		(fp_line
			(start 0.67945 0.3048)
			(end 0.120396 0.3048)
			(stroke
				(width 0.1)
				(type default)
			)
			(layer "F.Fab")
		)
		(fp_line
			(start 0.120396 0.3048)
			(end 0.120396 0.2794)
			(stroke
				(width 0.1)
				(type default)
			)
			(layer "F.Fab")
		)
		(fp_line
			(start -0.12065 0.3048)
			(end -0.67945 0.3048)
			(stroke
				(width 0.1)
				(type default)
			)
			(layer "F.Fab")
		)
		(fp_line
			(start -0.67945 0.3048)
			(end -0.67945 -0.305054)
			(stroke
				(width 0.1)
				(type default)
			)
			(layer "F.Fab")
		)
		(pad "1" smd circle
			(at -0.40005 0 90)
			(size 0 0)
			(layers "F.Cu" "F.Mask" "F.Paste")
			(net "P3V3_SSD15_CO_GATE")
		)
		(pad "2" smd circle
			(at 0.40005 0 90)
			(size 0 0)
			(layers "F.Cu" "F.Mask" "F.Paste")
			(net "GND")
		)
	)
	(footprint ""
		(layer "F.Cu")
		(at 130.11658 -246.362982)
		(property "Reference" "R6246"
			(at 0 0 0)
			(layer "F.SilkS")
			(hide yes)
			(effects
				(font
					(size 1.27 1.27)
				)
			)
		)
		(property "Value" ""
			(at 0 0 0)
			(layer "F.Fab")
			(effects
				(font
					(size 1.27 1.27)
				)
			)
		)
		(duplicate_pad_numbers_are_jumpers no)
		(fp_line
			(start -0.7874 -0.4064)
			(end 0.7874 -0.4064)
			(stroke
				(width 0.1524)
				(type default)
			)
			(layer "F.SilkS")
		)
		(fp_line
			(start -0.7874 0.4064)
			(end -0.7874 -0.4064)
			(stroke
				(width 0.1524)
				(type default)
			)
			(layer "F.SilkS")
		)
		(fp_line
			(start 0.7874 -0.4064)
			(end 0.7874 0.4064)
			(stroke
				(width 0.1524)
				(type default)
			)
			(layer "F.SilkS")
		)
		(fp_line
			(start 0.7874 0.4064)
			(end -0.7874 0.4064)
			(stroke
				(width 0.1524)
				(type default)
			)
			(layer "F.SilkS")
		)
		(fp_line
			(start -0.67945 -0.305054)
			(end -0.12065 -0.305054)
			(stroke
				(width 0.1)
				(type default)
			)
			(layer "F.Fab")
		)
		(fp_line
			(start -0.67945 0.3048)
			(end -0.67945 -0.305054)
			(stroke
				(width 0.1)
				(type default)
			)
			(layer "F.Fab")
		)
		(fp_line
			(start -0.12065 -0.305054)
			(end -0.12065 -0.2794)
			(stroke
				(width 0.1)
				(type default)
			)
			(layer "F.Fab")
		)
		(fp_line
			(start -0.12065 -0.2794)
			(end 0.12065 -0.2794)
			(stroke
				(width 0.1)
				(type default)
			)
			(layer "F.Fab")
		)
		(fp_line
			(start -0.12065 0.2794)
			(end -0.12065 0.3048)
			(stroke
				(width 0.1)
				(type default)
			)
			(layer "F.Fab")
		)
		(fp_line
			(start -0.12065 0.3048)
			(end -0.67945 0.3048)
			(stroke
				(width 0.1)
				(type default)
			)
			(layer "F.Fab")
		)
		(fp_line
			(start 0.120396 0.2794)
			(end -0.12065 0.2794)
			(stroke
				(width 0.1)
				(type default)
			)
			(layer "F.Fab")
		)
		(fp_line
			(start 0.120396 0.3048)
			(end 0.120396 0.2794)
			(stroke
				(width 0.1)
				(type default)
			)
			(layer "F.Fab")
		)
		(fp_line
			(start 0.12065 -0.3048)
			(end 0.67945 -0.3048)
			(stroke
				(width 0.1)
				(type default)
			)
			(layer "F.Fab")
		)
		(fp_line
			(start 0.12065 -0.2794)
			(end 0.12065 -0.3048)
			(stroke
				(width 0.1)
				(type default)
			)
			(layer "F.Fab")
		)
		(fp_line
			(start 0.67945 -0.3048)
			(end 0.67945 0.3048)
			(stroke
				(width 0.1)
				(type default)
			)
			(layer "F.Fab")
		)
		(fp_line
			(start 0.67945 0.3048)
			(end 0.120396 0.3048)
			(stroke
				(width 0.1)
				(type default)
			)
			(layer "F.Fab")
		)
		(pad "1" smd circle
			(at -0.40005 0)
			(size 0 0)
			(layers "F.Cu" "F.Mask" "F.Paste")
			(net "SMB_BIC_I2C6_MUX_VR_R_SDA")
		)
		(pad "2" smd circle
			(at 0.40005 0)
			(size 0 0)
			(layers "F.Cu" "F.Mask" "F.Paste")
			(net "SMB_HOTSWAP_SDA_R")
		)
	)
	(footprint ""
		(layer "F.Cu")
		(at 92.195904 -103.259128)
		(property "Reference" "C413"
			(at 0 0 0)
			(layer "F.SilkS")
			(hide yes)
			(effects
				(font
					(size 1.27 1.27)
				)
			)
		)
		(property "Value" ""
			(at 0 0 0)
			(layer "F.Fab")
			(effects
				(font
					(size 1.27 1.27)
				)
			)
		)
		(duplicate_pad_numbers_are_jumpers no)
		(fp_line
			(start -0.7874 -0.4064)
			(end 0.7874 -0.4064)
			(stroke
				(width 0.1524)
				(type default)
			)
			(layer "F.SilkS")
		)
		(fp_line
			(start -0.7874 0.4064)
			(end -0.7874 -0.4064)
			(stroke
				(width 0.1524)
				(type default)
			)
			(layer "F.SilkS")
		)
		(fp_line
			(start 0.7874 -0.4064)
			(end 0.7874 0.4064)
			(stroke
				(width 0.1524)
				(type default)
			)
			(layer "F.SilkS")
		)
		(fp_line
			(start 0.7874 0.4064)
			(end -0.7874 0.4064)
			(stroke
				(width 0.1524)
				(type default)
			)
			(layer "F.SilkS")
		)
		(fp_line
			(start -0.67945 -0.305054)
			(end -0.12065 -0.305054)
			(stroke
				(width 0.1)
				(type default)
			)
			(layer "F.Fab")
		)
		(fp_line
			(start -0.67945 0.3048)
			(end -0.67945 -0.305054)
			(stroke
				(width 0.1)
				(type default)
			)
			(layer "F.Fab")
		)
		(fp_line
			(start -0.12065 -0.305054)
			(end -0.12065 -0.2794)
			(stroke
				(width 0.1)
				(type default)
			)
			(layer "F.Fab")
		)
		(fp_line
			(start -0.12065 -0.2794)
			(end 0.12065 -0.2794)
			(stroke
				(width 0.1)
				(type default)
			)
			(layer "F.Fab")
		)
		(fp_line
			(start -0.12065 0.2794)
			(end -0.12065 0.3048)
			(stroke
				(width 0.1)
				(type default)
			)
			(layer "F.Fab")
		)
		(fp_line
			(start -0.12065 0.3048)
			(end -0.67945 0.3048)
			(stroke
				(width 0.1)
				(type default)
			)
			(layer "F.Fab")
		)
		(fp_line
			(start 0.120396 0.2794)
			(end -0.12065 0.2794)
			(stroke
				(width 0.1)
				(type default)
			)
			(layer "F.Fab")
		)
		(fp_line
			(start 0.120396 0.3048)
			(end 0.120396 0.2794)
			(stroke
				(width 0.1)
				(type default)
			)
			(layer "F.Fab")
		)
		(fp_line
			(start 0.12065 -0.3048)
			(end 0.67945 -0.3048)
			(stroke
				(width 0.1)
				(type default)
			)
			(layer "F.Fab")
		)
		(fp_line
			(start 0.12065 -0.2794)
			(end 0.12065 -0.3048)
			(stroke
				(width 0.1)
				(type default)
			)
			(layer "F.Fab")
		)
		(fp_line
			(start 0.67945 -0.3048)
			(end 0.67945 0.3048)
			(stroke
				(width 0.1)
				(type default)
			)
			(layer "F.Fab")
		)
		(fp_line
			(start 0.67945 0.3048)
			(end 0.120396 0.3048)
			(stroke
				(width 0.1)
				(type default)
			)
			(layer "F.Fab")
		)
		(pad "1" smd circle
			(at -0.40005 0)
			(size 0 0)
			(layers "F.Cu" "F.Mask" "F.Paste")
			(net "P12V_NIC1_R")
		)
		(pad "2" smd circle
			(at 0.40005 0)
			(size 0 0)
			(layers "F.Cu" "F.Mask" "F.Paste")
			(net "GND")
		)
	)
	(footprint ""
		(layer "F.Cu")
		(at 245.16588 -308.162452 90)
		(property "Reference" "PC262"
			(at 0 0 90)
			(layer "F.SilkS")
			(hide yes)
			(effects
				(font
					(size 1.27 1.27)
				)
			)
		)
		(property "Value" ""
			(at 0 0 90)
			(layer "F.Fab")
			(effects
				(font
					(size 1.27 1.27)
				)
			)
		)
		(duplicate_pad_numbers_are_jumpers no)
		(fp_line
			(start 0.7874 -0.4064)
			(end 0.7874 0.4064)
			(stroke
				(width 0.1524)
				(type default)
			)
			(layer "F.SilkS")
		)
		(fp_line
			(start -0.7874 -0.4064)
			(end 0.7874 -0.4064)
			(stroke
				(width 0.1524)
				(type default)
			)
			(layer "F.SilkS")
		)
		(fp_line
			(start 0.7874 0.4064)
			(end -0.7874 0.4064)
			(stroke
				(width 0.1524)
				(type default)
			)
			(layer "F.SilkS")
		)
		(fp_line
			(start -0.7874 0.4064)
			(end -0.7874 -0.4064)
			(stroke
				(width 0.1524)
				(type default)
			)
			(layer "F.SilkS")
		)
		(fp_line
			(start -0.12065 -0.305054)
			(end -0.12065 -0.2794)
			(stroke
				(width 0.1)
				(type default)
			)
			(layer "F.Fab")
		)
		(fp_line
			(start -0.67945 -0.305054)
			(end -0.12065 -0.305054)
			(stroke
				(width 0.1)
				(type default)
			)
			(layer "F.Fab")
		)
		(fp_line
			(start 0.67945 -0.3048)
			(end 0.67945 0.3048)
			(stroke
				(width 0.1)
				(type default)
			)
			(layer "F.Fab")
		)
		(fp_line
			(start 0.12065 -0.3048)
			(end 0.67945 -0.3048)
			(stroke
				(width 0.1)
				(type default)
			)
			(layer "F.Fab")
		)
		(fp_line
			(start 0.12065 -0.2794)
			(end 0.12065 -0.3048)
			(stroke
				(width 0.1)
				(type default)
			)
			(layer "F.Fab")
		)
		(fp_line
			(start -0.12065 -0.2794)
			(end 0.12065 -0.2794)
			(stroke
				(width 0.1)
				(type default)
			)
			(layer "F.Fab")
		)
		(fp_line
			(start 0.120396 0.2794)
			(end -0.12065 0.2794)
			(stroke
				(width 0.1)
				(type default)
			)
			(layer "F.Fab")
		)
		(fp_line
			(start -0.12065 0.2794)
			(end -0.12065 0.3048)
			(stroke
				(width 0.1)
				(type default)
			)
			(layer "F.Fab")
		)
		(fp_line
			(start 0.67945 0.3048)
			(end 0.120396 0.3048)
			(stroke
				(width 0.1)
				(type default)
			)
			(layer "F.Fab")
		)
		(fp_line
			(start 0.120396 0.3048)
			(end 0.120396 0.2794)
			(stroke
				(width 0.1)
				(type default)
			)
			(layer "F.Fab")
		)
		(fp_line
			(start -0.12065 0.3048)
			(end -0.67945 0.3048)
			(stroke
				(width 0.1)
				(type default)
			)
			(layer "F.Fab")
		)
		(fp_line
			(start -0.67945 0.3048)
			(end -0.67945 -0.305054)
			(stroke
				(width 0.1)
				(type default)
			)
			(layer "F.Fab")
		)
		(pad "1" smd circle
			(at -0.40005 0 90)
			(size 0 0)
			(layers "F.Cu" "F.Mask" "F.Paste")
			(net "P1V25_PEX2_REF")
		)
		(pad "2" smd circle
			(at 0.40005 0 90)
			(size 0 0)
			(layers "F.Cu" "F.Mask" "F.Paste")
			(net "SH_P1V25_PEX2_FB_N")
		)
	)
	(footprint ""
		(layer "F.Cu")
		(at 379.201934 -32.849312 90)
		(property "Reference" "R5698"
			(at 0 0 90)
			(layer "F.SilkS")
			(hide yes)
			(effects
				(font
					(size 1.27 1.27)
				)
			)
		)
		(property "Value" ""
			(at 0 0 90)
			(layer "F.Fab")
			(effects
				(font
					(size 1.27 1.27)
				)
			)
		)
		(duplicate_pad_numbers_are_jumpers no)
		(fp_line
			(start 0.7874 -0.4064)
			(end 0.7874 0.4064)
			(stroke
				(width 0.1524)
				(type default)
			)
			(layer "F.SilkS")
		)
		(fp_line
			(start -0.7874 -0.4064)
			(end 0.7874 -0.4064)
			(stroke
				(width 0.1524)
				(type default)
			)
			(layer "F.SilkS")
		)
		(fp_line
			(start 0.7874 0.4064)
			(end -0.7874 0.4064)
			(stroke
				(width 0.1524)
				(type default)
			)
			(layer "F.SilkS")
		)
		(fp_line
			(start -0.7874 0.4064)
			(end -0.7874 -0.4064)
			(stroke
				(width 0.1524)
				(type default)
			)
			(layer "F.SilkS")
		)
		(fp_line
			(start -0.12065 -0.305054)
			(end -0.12065 -0.2794)
			(stroke
				(width 0.1)
				(type default)
			)
			(layer "F.Fab")
		)
		(fp_line
			(start -0.67945 -0.305054)
			(end -0.12065 -0.305054)
			(stroke
				(width 0.1)
				(type default)
			)
			(layer "F.Fab")
		)
		(fp_line
			(start 0.67945 -0.3048)
			(end 0.67945 0.3048)
			(stroke
				(width 0.1)
				(type default)
			)
			(layer "F.Fab")
		)
		(fp_line
			(start 0.12065 -0.3048)
			(end 0.67945 -0.3048)
			(stroke
				(width 0.1)
				(type default)
			)
			(layer "F.Fab")
		)
		(fp_line
			(start 0.12065 -0.2794)
			(end 0.12065 -0.3048)
			(stroke
				(width 0.1)
				(type default)
			)
			(layer "F.Fab")
		)
		(fp_line
			(start -0.12065 -0.2794)
			(end 0.12065 -0.2794)
			(stroke
				(width 0.1)
				(type default)
			)
			(layer "F.Fab")
		)
		(fp_line
			(start 0.120396 0.2794)
			(end -0.12065 0.2794)
			(stroke
				(width 0.1)
				(type default)
			)
			(layer "F.Fab")
		)
		(fp_line
			(start -0.12065 0.2794)
			(end -0.12065 0.3048)
			(stroke
				(width 0.1)
				(type default)
			)
			(layer "F.Fab")
		)
		(fp_line
			(start 0.67945 0.3048)
			(end 0.120396 0.3048)
			(stroke
				(width 0.1)
				(type default)
			)
			(layer "F.Fab")
		)
		(fp_line
			(start 0.120396 0.3048)
			(end 0.120396 0.2794)
			(stroke
				(width 0.1)
				(type default)
			)
			(layer "F.Fab")
		)
		(fp_line
			(start -0.12065 0.3048)
			(end -0.67945 0.3048)
			(stroke
				(width 0.1)
				(type default)
			)
			(layer "F.Fab")
		)
		(fp_line
			(start -0.67945 0.3048)
			(end -0.67945 -0.305054)
			(stroke
				(width 0.1)
				(type default)
			)
			(layer "F.Fab")
		)
		(pad "1" smd circle
			(at -0.40005 0 90)
			(size 0 0)
			(layers "F.Cu" "F.Mask" "F.Paste")
			(net "RST_SMB_SSD13_ISO_R_N")
		)
		(pad "2" smd circle
			(at 0.40005 0 90)
			(size 0 0)
			(layers "F.Cu" "F.Mask" "F.Paste")
			(net "RST_SMB_SSD13_ISO_N")
		)
	)
)
